FILE_TYPE = CONNECTIVITY;
{Allegro Design Entry HDL 17.4-2019 S026 (4007227) 1/17/2022}
"PAGE_NUMBER" = 387;
0"NC";
1"GND\g";
2"GND\g";
3"GND\g";
4"GND\g";
5"SMB_RT_CPU0_P0_ROM_R_SDA";
6"SMB_RT_CPU0_P0_ROM_SDA";
7"SMB_RT_CPU0_P0_ROM_R_SCL";
8"SMB_RT_CPU0_P0_ROM_SCL";
9"P1V8_CPU0_RT_1D\g";
10"U11_E2";
%"P1V0"
"1","(-4925,5375)","0","pure_quanta_power","I20";
;
HDL_POWER"P1V8_CPU0_RT_1D"
CDS_LIB"pure_quanta_power";
"A"9;
%"Q_CAP"
"1","(-5225,5025)","0","pure_quanta","I21";
;
LOCATION"C7510"
$SEC"1"
CDS_SEC"1"
VOLTAGE"10V"
TOLERANCE"10%"
VALUE"0.1UF"
PACK_TYPE"C0201"
MATERIAL"X7S"
CDS_LIB"pure_quanta"
PART_NUMBER"CH4102K6E00";
"B"
$PN"2"1;
"A"
$PN"1"9;
%"UNIVERSAL_GND"
"1","(-5225,4750)","0","pure_quanta_power","I22";
;
CDS_LIB"pure_quanta_power"
HDL_POWER"GND";
"A"1;
%"UNIVERSAL_GND"
"1","(-4900,4575)","7","pure_quanta_power","I23";
;
CDS_LIB"pure_quanta_power"
HDL_POWER"GND";
"A"2;
%"Q_RES"
"2","(-3750,4375)","0","pure_quanta","I24";
;
LOCATION"R6822"
$SEC"1"
CDS_SEC"1"
VALUE"1K"
WATTAGE"1/20W"
TOLERANCE"1%"
MATERIAL"CHIP"
PACK_TYPE"0201LF"
CDS_LIB"pure_quanta"
PART_NUMBER"CS21001FE07";
"A"
$PN"1"10;
"B"
$PN"2"4;
%"UNIVERSAL_GND"
"1","(-3900,4300)","0","pure_quanta_power","I25";
;
CDS_LIB"pure_quanta_power"
HDL_POWER"GND";
"A"3;
%"UNIVERSAL_GND"
"1","(-3750,3950)","0","pure_quanta_power","I26";
;
CDS_LIB"pure_quanta_power"
HDL_POWER"GND";
"A"4;
%"M24M02DRMN6TP"
"1","(-4425,4550)","0","pure_quanta","I3";
;
LOCATION"U11"
$SEC"1"
CDS_SEC"1"
MATERIAL"IC"
PART_TYPE"SMLF"
VALUE"M24M02-DRMN6TP"
NEEDS_NO_SIZE"TRUE"
CDS_LMAN_SYM_OUTLINE"-175,125,175,-125"
CDS_LIB"pure_quanta"
PART_NUMBER"AKE33Z00600";
"DU1"
$PN"1"0;
"DU2"
$PN"2"0;
"E2"
$PN"3"10;
"VSS"
$PN"4"3;
"SDA"
$PN"5"6;
"SCL"
$PN"6"8;
"WC_N \B"
$PN"7"2;
"VCC"
$PN"8"9;
%"Q_RES"
"1","(-5850,4525)","0","pure_quanta","I6";
;
LOCATION"R668"
$SEC"1"
CDS_SEC"1"
PACK_TYPE"0201LF"
MATERIAL"CHIP"
WATTAGE"1/20W"
VALUE"33.2"
TOLERANCE"1%"
CDS_LIB"pure_quanta"
PART_NUMBER"CS03321FE09";
"B"
$PN"2"8;
"A"
$PN"1"7;
%"Q_RES"
"1","(-5850,4475)","0","pure_quanta","I7";
;
LOCATION"R669"
$SEC"1"
CDS_SEC"1"
CDS_LIB"pure_quanta"
MATERIAL"CHIP"
WATTAGE"1/20W"
PACK_TYPE"0201LF"
VALUE"33.2"
TOLERANCE"1%"
PART_NUMBER"CS03321FE09";
"B"
$PN"2"6;
"A"
$PN"1"5;
END.
